#ISCELL
  mstr_misc dns *
  *
#ISCELL
  mstr_symbols cad_note *
  *
#ISCELL
  mstr_symbols design_note *
  *
#ISCELL
  mstr_symbols intel_corp_bpage *
  *
#CELL
  mstr_discrete res *
  page158_i100
#ISCELL
  mstr_standard offpage *
  page158_i124
#ISCELL
  mstr_standard offpage *
  page158_i125
#ISCELL
  mstr_standard offpage *
  page158_i126
#ISCELL
  mstr_standard offpage *
  page158_i127
#ISCELL
  mstr_standard offpage *
  page158_i128
#ISCELL
  mstr_standard offpage *
  page158_i129
#CELL
  mstr_discrete led *
  page158_i130
#CELL
  mstr_discrete res *
  page158_i131
#ISCELL
  mstr_standard offpage *
  page158_i132
#CELL
  mstr_discrete led *
  page158_i134
#ISCELL
  mstr_symbols p3v3_stby *
  page158_i135
#CELL
  mstr_discrete res *
  page158_i136
#ISCELL
  mstr_standard offpage *
  page158_i137
#ISCELL
  mstr_standard offpage *
  page158_i144
#ISCELL
  mstr_standard offpage *
  page158_i147
#CELL
  mstr_discrete res *
  page158_i148
#CELL
  mstr_discrete res *
  page158_i149
#CELL
  mstr_discrete res *
  page158_i150
#CELL
  mstr_discrete res *
  page158_i152
#CELL
  mstr_discrete res *
  page158_i153
#CELL
  mstr_discrete res *
  page158_i154
#CELL
  mstr_discrete res *
  page158_i155
#ISCELL
  mstr_symbols p3v3_stby *
  page158_i156
#CELL
  dev_discrete cap_a *
  page158_i70
#ISCELL
  mstr_symbols gnd *
  page158_i72
#CELL
  mstr_analog fsa3357 *
  page158_i74
#CELL
  mstr_analog fsa3357 *
  page158_i75
#ISCELL
  mstr_symbols gnd *
  page158_i76
#ISCELL
  mstr_symbols gnd *
  page158_i77
#ISCELL
  mstr_symbols p3v3_stby *
  page158_i78
#ISCELL
  mstr_symbols p3v3_stby *
  page158_i79
#ISCELL
  mstr_standard offpage *
  page158_i85
#CELL
  mstr_discrete res *
  page158_i86
#ISCELL
  mstr_standard offpage *
  page158_i87
#CELL
  mstr_discrete res *
  page158_i91
#ISCELL
  mstr_standard offpage *
  page158_i92
#ISCELL
  mstr_standard offpage *
  page158_i93
#ISCELL
  mstr_standard offpage *
  page158_i94
#ISCELL
  mstr_standard offpage *
  page158_i95
#CELL
  dev_discrete cap_a *
  page158_i97
#ISCELL
  mstr_symbols gnd *
  page158_i98
#CELL
  mstr_discrete res *
  page158_i99
